# T6G (Grand Teton) — schematic netlist excerpt (pin names and nets, part order shuffled) for the footprints in the layout excerpt that follows; sources: Cadence DE-HDL packaged netlist, KiCad conversion of 04192023_DAF0TMB3IC0_F0TG_MB_C_brd_V02_OCP.brd

C2134  Q_CAP  22UF 4V 20% X6S  pkg C0402  page 68 : A = PVDDCR_SOC_P0 ; B = GND
R3047  Q_RES  0 5% CHIP  pkg 0402LF  page 253 : A = MB0_P12V_STBY_PWRGD ; B = PWRGD_PS_PWROK_PLD

(kicad_pcb
	(version 20260206)
	(generator "pcbnew")
	(generator_version "10.0")
	(general
		(thickness 1.6)
		(legacy_teardrops no)
	)
	(paper "A4")
	(title_block
		(title "04192023_DAF0TMB3IC0_F0TG_MB_C_brd_V02_OCP.brd")
		(comment 1 "Grand Teton / footprints 6888-6889 of 8354")
	)
	(layers
		(0 "F.Cu" signal "TOP")
		(4 "In1.Cu" signal "GND")
		(6 "In2.Cu" signal "IN1")
		(8 "In3.Cu" signal "GND1")
		(10 "In4.Cu" signal "IN2")
		(12 "In5.Cu" signal "GND2")
		(14 "In6.Cu" signal "IN3")
		(16 "In7.Cu" signal "GND3")
		(18 "In8.Cu" signal "VCC")
		(20 "In9.Cu" signal "VCC1")
		(22 "In10.Cu" signal "GND4")
		(24 "In11.Cu" signal "IN4")
		(26 "In12.Cu" signal "GND5")
		(28 "In13.Cu" signal "IN5")
		(30 "In14.Cu" signal "GND6")
		(32 "In15.Cu" signal "IN6")
		(34 "In16.Cu" signal "GND7")
		(2 "B.Cu" signal "BOTTOM")
		(9 "F.Adhes" user "F.Adhesive")
		(11 "B.Adhes" user "B.Adhesive")
		(13 "F.Paste" user "Package Geometry/Pastemask Top")
		(15 "B.Paste" user "Package Geometry/Pastemask Bottom")
		(5 "F.SilkS" user "Ref Des/Silkscreen Top")
		(7 "B.SilkS" user "Ref Des/Silkscreen Bottom")
		(1 "F.Mask" user "Board Geometry/Soldermask Top")
		(3 "B.Mask" user "Board Geometry/Soldermask Bottom")
		(17 "Dwgs.User" user "User.Drawings")
		(19 "Cmts.User" user "User.Comments")
		(21 "Eco1.User" user "User.Eco1")
		(23 "Eco2.User" user "User.Eco2")
		(25 "Edge.Cuts" user "Board Geometry/Outline")
		(27 "Margin" user)
		(31 "F.CrtYd" user "Package Geometry/Place Bound Top")
		(29 "B.CrtYd" user "Package Geometry/Place Bound Bottom")
		(35 "F.Fab" user "Ref Des/Assembly Top")
		(33 "B.Fab" user "Ref Des/Assembly Bottom")
	)
	(footprint ""
		(layer "B.Cu")
		(at 369.646454 -252.54331)
		(property "Reference" "C2134"
			(at 0 0 0)
			(layer "B.SilkS")
			(hide yes)
			(effects
				(font
					(size 1.27 1.27)
				)
				(justify mirror)
			)
		)
		(property "Value" ""
			(at 0 0 0)
			(layer "B.Fab")
			(effects
				(font
					(size 1.27 1.27)
				)
				(justify mirror)
			)
		)
		(duplicate_pad_numbers_are_jumpers no)
		(fp_line
			(start -0.7874 -0.4064)
			(end -0.7874 0.4064)
			(stroke
				(width 0.1524)
				(type default)
			)
			(layer "B.SilkS")
		)
		(fp_line
			(start -0.7874 0.4064)
			(end 0.7874 0.4064)
			(stroke
				(width 0.1524)
				(type default)
			)
			(layer "B.SilkS")
		)
		(fp_line
			(start 0.7874 -0.4064)
			(end -0.7874 -0.4064)
			(stroke
				(width 0.1524)
				(type default)
			)
			(layer "B.SilkS")
		)
		(fp_line
			(start 0.7874 0.4064)
			(end 0.7874 -0.4064)
			(stroke
				(width 0.1524)
				(type default)
			)
			(layer "B.SilkS")
		)
		(fp_line
			(start -0.67945 -0.3048)
			(end -0.67945 0.3048)
			(stroke
				(width 0.1)
				(type default)
			)
			(layer "B.Fab")
		)
		(fp_line
			(start -0.67945 0.3048)
			(end -0.120396 0.3048)
			(stroke
				(width 0.1)
				(type default)
			)
			(layer "B.Fab")
		)
		(fp_line
			(start -0.12065 -0.3048)
			(end -0.67945 -0.3048)
			(stroke
				(width 0.1)
				(type default)
			)
			(layer "B.Fab")
		)
		(fp_line
			(start -0.12065 -0.2794)
			(end -0.12065 -0.3048)
			(stroke
				(width 0.1)
				(type default)
			)
			(layer "B.Fab")
		)
		(fp_line
			(start -0.120396 0.2794)
			(end 0.12065 0.2794)
			(stroke
				(width 0.1)
				(type default)
			)
			(layer "B.Fab")
		)
		(fp_line
			(start -0.120396 0.3048)
			(end -0.120396 0.2794)
			(stroke
				(width 0.1)
				(type default)
			)
			(layer "B.Fab")
		)
		(fp_line
			(start 0.12065 -0.305054)
			(end 0.12065 -0.2794)
			(stroke
				(width 0.1)
				(type default)
			)
			(layer "B.Fab")
		)
		(fp_line
			(start 0.12065 -0.2794)
			(end -0.12065 -0.2794)
			(stroke
				(width 0.1)
				(type default)
			)
			(layer "B.Fab")
		)
		(fp_line
			(start 0.12065 0.2794)
			(end 0.12065 0.3048)
			(stroke
				(width 0.1)
				(type default)
			)
			(layer "B.Fab")
		)
		(fp_line
			(start 0.12065 0.3048)
			(end 0.67945 0.3048)
			(stroke
				(width 0.1)
				(type default)
			)
			(layer "B.Fab")
		)
		(fp_line
			(start 0.67945 -0.305054)
			(end 0.12065 -0.305054)
			(stroke
				(width 0.1)
				(type default)
			)
			(layer "B.Fab")
		)
		(fp_line
			(start 0.67945 0.3048)
			(end 0.67945 -0.305054)
			(stroke
				(width 0.1)
				(type default)
			)
			(layer "B.Fab")
		)
		(pad "1" smd circle
			(at 0.40005 0 180)
			(size 0 0)
			(layers "B.Cu" "B.Mask" "B.Paste")
			(net "PVDDCR_SOC_P0")
		)
		(pad "2" smd circle
			(at -0.40005 0 180)
			(size 0 0)
			(layers "B.Cu" "B.Mask" "B.Paste")
			(net "GND")
		)
	)
	(footprint ""
		(layer "B.Cu")
		(at 311.427876 -76.489814 -90)
		(property "Reference" "R3047"
			(at 0 0 90)
			(layer "B.SilkS")
			(hide yes)
			(effects
				(font
					(size 1.27 1.27)
				)
				(justify mirror)
			)
		)
		(property "Value" ""
			(at 0 0 90)
			(layer "B.Fab")
			(effects
				(font
					(size 1.27 1.27)
				)
				(justify mirror)
			)
		)
		(duplicate_pad_numbers_are_jumpers no)
		(fp_line
			(start -0.7874 0.4064)
			(end 0.7874 0.4064)
			(stroke
				(width 0.1524)
				(type default)
			)
			(layer "B.SilkS")
		)
		(fp_line
			(start 0.7874 0.4064)
			(end 0.7874 -0.4064)
			(stroke
				(width 0.1524)
				(type default)
			)
			(layer "B.SilkS")
		)
		(fp_line
			(start -0.7874 -0.4064)
			(end -0.7874 0.4064)
			(stroke
				(width 0.1524)
				(type default)
			)
			(layer "B.SilkS")
		)
		(fp_line
			(start 0.7874 -0.4064)
			(end -0.7874 -0.4064)
			(stroke
				(width 0.1524)
				(type default)
			)
			(layer "B.SilkS")
		)
		(fp_line
			(start -0.67945 0.3048)
			(end -0.120396 0.3048)
			(stroke
				(width 0.1)
				(type default)
			)
			(layer "B.Fab")
		)
		(fp_line
			(start -0.120396 0.3048)
			(end -0.120396 0.2794)
			(stroke
				(width 0.1)
				(type default)
			)
			(layer "B.Fab")
		)
		(fp_line
			(start 0.12065 0.3048)
			(end 0.67945 0.3048)
			(stroke
				(width 0.1)
				(type default)
			)
			(layer "B.Fab")
		)
		(fp_line
			(start 0.67945 0.3048)
			(end 0.67945 -0.305054)
			(stroke
				(width 0.1)
				(type default)
			)
			(layer "B.Fab")
		)
		(fp_line
			(start -0.120396 0.2794)
			(end 0.12065 0.2794)
			(stroke
				(width 0.1)
				(type default)
			)
			(layer "B.Fab")
		)
		(fp_line
			(start 0.12065 0.2794)
			(end 0.12065 0.3048)
			(stroke
				(width 0.1)
				(type default)
			)
			(layer "B.Fab")
		)
		(fp_line
			(start -0.12065 -0.2794)
			(end -0.12065 -0.3048)
			(stroke
				(width 0.1)
				(type default)
			)
			(layer "B.Fab")
		)
		(fp_line
			(start 0.12065 -0.2794)
			(end -0.12065 -0.2794)
			(stroke
				(width 0.1)
				(type default)
			)
			(layer "B.Fab")
		)
		(fp_line
			(start -0.67945 -0.3048)
			(end -0.67945 0.3048)
			(stroke
				(width 0.1)
				(type default)
			)
			(layer "B.Fab")
		)
		(fp_line
			(start -0.12065 -0.3048)
			(end -0.67945 -0.3048)
			(stroke
				(width 0.1)
				(type default)
			)
			(layer "B.Fab")
		)
		(fp_line
			(start 0.12065 -0.305054)
			(end 0.12065 -0.2794)
			(stroke
				(width 0.1)
				(type default)
			)
			(layer "B.Fab")
		)
		(fp_line
			(start 0.67945 -0.305054)
			(end 0.12065 -0.305054)
			(stroke
				(width 0.1)
				(type default)
			)
			(layer "B.Fab")
		)
		(pad "1" smd circle
			(at 0.40005 0 90)
			(size 0 0)
			(layers "B.Cu" "B.Mask" "B.Paste")
			(net "MB0_P12V_STBY_PWRGD")
		)
		(pad "2" smd circle
			(at -0.40005 0 90)
			(size 0 0)
			(layers "B.Cu" "B.Mask" "B.Paste")
			(net "PWRGD_PS_PWROK_PLD")
		)
	)
)
